FILE_TYPE = CONNECTIVITY;
{Allegro Design Entry HDL 16.5-S008 (v16-5-13Y) 10/18/2011}
"PAGE_NUMBER" = 1;
0"NC";
1"P3V3_STBY \G";
2"G\I";
%"SYNONYM"
"1","(1850,2050)","0","mstr_standard","4P";
;
NEEDS_NO_SIZE"TRUE"
BODY_TYPE"PLUMBING"
CDS_LIB"mstr_standard";
"A\NWC\NAC"2;
"A\NWC\NAC"1;
%"DRAWING"
"2","(1275,1750)","0","mstr_standard","";
;
LAST_MODIFIED"Tue Oct 25 14:26:28 2011"
TITLE"P3V3_STBY"
ABBREV"P3V3_STBY";
END.
